#ISCELL
  mstr_misc dns *
  *
#ISCELL
  pure_quanta quanta_title_block_c *
  *
#ISCELL
  pure_quanta_power universal_gnd *
  page475_i10
#CELL
  pure_quanta q_res *
  page475_i105
#CELL
  pure_quanta q_cap *
  page475_i118
#CELL
  pure_quanta q_res *
  page475_i119
#CELL
  pure_quanta q_res *
  page475_i120
#CELL
  pure_quanta q_cap *
  page475_i121
#CELL
  pure_quanta q_cap *
  page475_i123
#CELL
  pure_quanta q_res *
  page475_i125
#CELL
  pure_quanta q_res *
  page475_i127
#CELL
  pure_quanta q_res *
  page475_i128
#CELL
  pure_quanta q_res *
  page475_i131
#CELL
  pure_quanta q_cap *
  page475_i132
#CELL
  pure_quanta q_res *
  page475_i135
#CELL
  pure_quanta q_res *
  page475_i136
#CELL
  pure_quanta q_res *
  page475_i138
#CELL
  pure_quanta q_cap *
  page475_i144
#CELL
  pure_quanta q_cap *
  page475_i145
#CELL
  pure_quanta q_cap *
  page475_i146
#CELL
  pure_quanta q_cap *
  page475_i148
#CELL
  pure_quanta q_res *
  page475_i150
#CELL
  pure_quanta q_cap *
  page475_i151
#ISCELL
  pure_quanta_power universal_gnd *
  page475_i154
#CELL
  pure_quanta q_res *
  page475_i158
#ISCELL
  pure_quanta_power vcc15 *
  page475_i159
#ISCELL
  standard offpage *
  page475_i16
#CELL
  pure_quanta q_res *
  page475_i160
#CELL
  pure_quanta q_res *
  page475_i161
#ISCELL
  pure_quanta_power universal_gnd *
  page475_i162
#ISCELL
  pure_quanta_power vcc15 *
  page475_i164
#CELL
  pure_quanta q_res *
  page475_i165
#CELL
  pure_quanta q_res *
  page475_i166
#CELL
  pure_quanta q_res *
  page475_i167
#CELL
  pure_quanta q_res *
  page475_i168
#CELL
  pure_quanta q_res *
  page475_i169
#ISCELL
  standard offpage *
  page475_i17
#ISCELL
  pure_quanta_power universal_gnd *
  page475_i172
#ISCELL
  pure_quanta_power vcc15 *
  page475_i176
#CELL
  pure_quanta q_res *
  page475_i178
#CELL
  pure_quanta q_res *
  page475_i183
#ISCELL
  standard offpage *
  page475_i186
#ISCELL
  standard offpage *
  page475_i187
#CELL
  pure_quanta q_res *
  page475_i188
#ISCELL
  pure_quanta_power universal_gnd *
  page475_i189
#CELL
  pure_quanta q_res *
  page475_i190
#CELL
  pure_quanta q_res *
  page475_i191
#CELL
  pure_quanta q_res *
  page475_i192
#CELL
  pure_quanta q_res *
  page475_i193
#ISCELL
  pure_quanta_power universal_gnd *
  page475_i194
#ISCELL
  pure_quanta_power universal_gnd *
  page475_i195
#ISCELL
  pure_quanta_power universal_gnd *
  page475_i196
#ISCELL
  pure_quanta_power universal_gnd *
  page475_i197
#CELL
  pure_quanta q_res *
  page475_i198
#ISCELL
  pure_quanta_power universal_gnd *
  page475_i199
#ISCELL
  pure_quanta_power universal_gnd *
  page475_i2
#ISCELL
  pure_quanta_power vcc15 *
  page475_i200
#ISCELL
  pure_quanta_power universal_gnd *
  page475_i202
#ISCELL
  pure_quanta_power universal_gnd *
  page475_i203
#CELL
  pure_quanta q_res *
  page475_i204
#ISCELL
  pure_quanta_power universal_gnd *
  page475_i205
#CELL
  pure_quanta q_res *
  page475_i207
#CELL
  pure_quanta q_res *
  page475_i208
#ISCELL
  pure_quanta_power universal_gnd *
  page475_i209
#CELL
  pure_quanta q_res *
  page475_i210
#ISCELL
  pure_quanta_power vcc15 *
  page475_i211
#CELL
  pure_quanta q_res *
  page475_i212
#CELL
  pure_quanta q_res *
  page475_i213
#CELL
  pure_quanta q_short *
  page475_i214
#CELL
  pure_quanta q_short *
  page475_i215
#ISCELL
  standard offpage *
  page475_i23
#ISCELL
  standard offpage *
  page475_i24
#CELL
  pure_quanta q_res *
  page475_i32
#CELL
  pure_quanta q_res *
  page475_i34
#ISCELL
  pure_quanta_power universal_gnd *
  page475_i35
#ISCELL
  pure_quanta_power vcc15 *
  page475_i36
#ISCELL
  pure_quanta_power vcc15 *
  page475_i37
#ISCELL
  pure_quanta_power universal_gnd *
  page475_i41
#CELL
  pure_quanta isl69260irazt *
  page475_i42
#ISCELL
  pure_quanta_power universal_gnd *
  page475_i5
#ISCELL
  pure_quanta_power vcc15 *
  page475_i51
#ISCELL
  pure_quanta_power universal_gnd *
  page475_i55
#ISCELL
  pure_quanta_power universal_gnd *
  page475_i56
#ISCELL
  pure_quanta_power universal_gnd *
  page475_i58
#ISCELL
  standard offpage *
  page475_i69
#ISCELL
  pure_quanta_power vcc15 *
  page475_i74
#ISCELL
  standard offpage *
  page475_i86
#ISCELL
  standard offpage *
  page475_i88
#ISCELL
  pure_quanta_power universal_gnd *
  page475_i89
#ISCELL
  standard offpage *
  page475_i90
#ISCELL
  pure_quanta_power universal_gnd *
  page475_i91
#ISCELL
  pure_quanta_power vcc15 *
  page475_i93
#CELL
  pure_quanta q_res *
  page475_i94
#CELL
  pure_quanta q_res *
  page475_i95
